# T6G (Grand Teton) — schematic netlist excerpt (pin names and nets, part order shuffled) for the footprints in the layout excerpt that follows; sources: Cadence DE-HDL packaged netlist, KiCad conversion of 04192023_DAF0TMB3IC0_F0TG_MB_C_brd_V02_OCP.brd

C896  Q_CAP_DIFFBUS  DIFF BUS_0.22UF 6.3V 20% X6S  pkg C0201  page 64 : \1\ = P5E_CPU0_P3_TX_C_DN<2> ; \2\ = P5E_CPU0_P3_TX_DN<2>
R676  Q_RES  49.9 1% CHIP  pkg 0201LF  page 287 : A = SMB_RT_CPU0_P1_ROM_MUX_1D_SCL ; B = SMB_RT_CPU0_P1_ROM_MUX_1D_R_SCL
D7  Q_LED  IC  pkg SMLF  page 85 : A = BMC_FPGA_LED2_R_N ; C = BMC_FPGA_LED2_N

(kicad_pcb
	(version 20260206)
	(generator "pcbnew")
	(generator_version "10.0")
	(general
		(thickness 1.6)
		(legacy_teardrops no)
	)
	(paper "A4")
	(title_block
		(title "04192023_DAF0TMB3IC0_F0TG_MB_C_brd_V02_OCP.brd")
		(comment 1 "Grand Teton / footprints 4084-4086 of 8354")
	)
	(layers
		(0 "F.Cu" signal "TOP")
		(4 "In1.Cu" signal "GND")
		(6 "In2.Cu" signal "IN1")
		(8 "In3.Cu" signal "GND1")
		(10 "In4.Cu" signal "IN2")
		(12 "In5.Cu" signal "GND2")
		(14 "In6.Cu" signal "IN3")
		(16 "In7.Cu" signal "GND3")
		(18 "In8.Cu" signal "VCC")
		(20 "In9.Cu" signal "VCC1")
		(22 "In10.Cu" signal "GND4")
		(24 "In11.Cu" signal "IN4")
		(26 "In12.Cu" signal "GND5")
		(28 "In13.Cu" signal "IN5")
		(30 "In14.Cu" signal "GND6")
		(32 "In15.Cu" signal "IN6")
		(34 "In16.Cu" signal "GND7")
		(2 "B.Cu" signal "BOTTOM")
		(9 "F.Adhes" user "F.Adhesive")
		(11 "B.Adhes" user "B.Adhesive")
		(13 "F.Paste" user "Package Geometry/Pastemask Top")
		(15 "B.Paste" user "Package Geometry/Pastemask Bottom")
		(5 "F.SilkS" user "Ref Des/Silkscreen Top")
		(7 "B.SilkS" user "Ref Des/Silkscreen Bottom")
		(1 "F.Mask" user "Board Geometry/Soldermask Top")
		(3 "B.Mask" user "Board Geometry/Soldermask Bottom")
		(17 "Dwgs.User" user "User.Drawings")
		(19 "Cmts.User" user "User.Comments")
		(21 "Eco1.User" user "User.Eco1")
		(23 "Eco2.User" user "User.Eco2")
		(25 "Edge.Cuts" user "Board Geometry/Outline")
		(27 "Margin" user)
		(31 "F.CrtYd" user "Package Geometry/Place Bound Top")
		(29 "B.CrtYd" user "Package Geometry/Place Bound Bottom")
		(35 "F.Fab" user "Ref Des/Assembly Top")
		(33 "B.Fab" user "Ref Des/Assembly Bottom")
	)
	(footprint ""
		(layer "F.Cu")
		(at 330.63434 -16.178276 90)
		(property "Reference" "D7"
			(at -3.12166 0.79375 90)
			(unlocked yes)
			(layer "F.SilkS")
			(effects
				(font
					(size 0.7874 0.5842)
					(thickness 0.1524)
				)
				(justify left)
			)
		)
		(property "Value" ""
			(at 0 0 90)
			(layer "F.Fab")
			(effects
				(font
					(size 1.27 1.27)
				)
			)
		)
		(duplicate_pad_numbers_are_jumpers no)
		(fp_line
			(start 1.778 -0.5588)
			(end 1.3208 -0.5588)
			(stroke
				(width 0.1524)
				(type default)
			)
			(layer "F.SilkS")
		)
		(fp_line
			(start 1.778 -0.5588)
			(end 1.778 0.5588)
			(stroke
				(width 0.1524)
				(type default)
			)
			(layer "F.SilkS")
		)
		(fp_line
			(start 1.4732 -0.5588)
			(end 1.4732 0.5588)
			(stroke
				(width 0.1524)
				(type default)
			)
			(layer "F.SilkS")
		)
		(fp_line
			(start 1.3208 -0.5588)
			(end 1.3208 0.5588)
			(stroke
				(width 0.1524)
				(type default)
			)
			(layer "F.SilkS")
		)
		(fp_line
			(start -1.3208 -0.5588)
			(end 1.3208 -0.5588)
			(stroke
				(width 0.1524)
				(type default)
			)
			(layer "F.SilkS")
		)
		(fp_line
			(start 1.778 0.5588)
			(end 1.3208 0.5588)
			(stroke
				(width 0.1524)
				(type default)
			)
			(layer "F.SilkS")
		)
		(fp_line
			(start 1.6256 0.5588)
			(end 1.6256 -0.5588)
			(stroke
				(width 0.1524)
				(type default)
			)
			(layer "F.SilkS")
		)
		(fp_line
			(start 1.3208 0.5588)
			(end -1.3208 0.5588)
			(stroke
				(width 0.1524)
				(type default)
			)
			(layer "F.SilkS")
		)
		(fp_line
			(start -1.3208 0.5588)
			(end -1.3208 -0.5588)
			(stroke
				(width 0.1524)
				(type default)
			)
			(layer "F.SilkS")
		)
		(fp_line
			(start 0.899922 -0.40005)
			(end 0.899922 0.40005)
			(stroke
				(width 0.1)
				(type default)
			)
			(layer "F.Fab")
		)
		(fp_line
			(start -0.899922 -0.40005)
			(end 0.899922 -0.40005)
			(stroke
				(width 0.1)
				(type default)
			)
			(layer "F.Fab")
		)
		(fp_line
			(start 0.899922 0.40005)
			(end -0.899922 0.40005)
			(stroke
				(width 0.1)
				(type default)
			)
			(layer "F.Fab")
		)
		(fp_line
			(start -0.899922 0.40005)
			(end -0.899922 -0.40005)
			(stroke
				(width 0.1)
				(type default)
			)
			(layer "F.Fab")
		)
		(fp_text user "-"
			(at 1.651 -0.96901 90)
			(unlocked yes)
			(layer "F.SilkS")
			(effects
				(font
					(size 1.905 1.4224)
					(thickness 0.1524)
				)
				(justify left)
			)
		)
		(fp_text user "+"
			(at -2.57302 -0.59055 90)
			(unlocked yes)
			(layer "F.SilkS")
			(effects
				(font
					(size 1.905 1.4224)
					(thickness 0.1524)
				)
				(justify left)
			)
		)
		(fp_text user "-"
			(at 1.651 -0.22225 90)
			(unlocked yes)
			(layer "F.Fab")
			(effects
				(font
					(size 1.905 1.4224)
					(thickness 0.1524)
				)
				(justify left)
			)
		)
		(fp_text user "+"
			(at -2.6162 -0.22225 90)
			(unlocked yes)
			(layer "F.Fab")
			(effects
				(font
					(size 1.905 1.4224)
					(thickness 0.1524)
				)
				(justify left)
			)
		)
		(pad "A" smd rect
			(at -0.750062 0 90)
			(size 0.8128 0.8128)
			(layers "F.Cu" "F.Mask" "F.Paste")
			(net "BMC_FPGA_LED2_R_N")
		)
		(pad "C" smd rect
			(at 0.750062 0 90)
			(size 0.8128 0.8128)
			(layers "F.Cu" "F.Mask" "F.Paste")
			(net "BMC_FPGA_LED2_N")
		)
	)
	(footprint ""
		(layer "F.Cu")
		(at 330.932536 -387.350254)
		(property "Reference" "R676"
			(at 0 0 0)
			(layer "F.SilkS")
			(hide yes)
			(effects
				(font
					(size 1.27 1.27)
				)
			)
		)
		(property "Value" ""
			(at 0 0 0)
			(layer "F.Fab")
			(effects
				(font
					(size 1.27 1.27)
				)
			)
		)
		(duplicate_pad_numbers_are_jumpers no)
		(fp_line
			(start -0.32512 -0.175006)
			(end 0.32512 -0.175006)
			(stroke
				(width 0.1)
				(type default)
			)
			(layer "F.Fab")
		)
		(fp_line
			(start -0.32512 0.175006)
			(end -0.32512 -0.175006)
			(stroke
				(width 0.1)
				(type default)
			)
			(layer "F.Fab")
		)
		(fp_line
			(start 0.32512 -0.175006)
			(end 0.32512 0.175006)
			(stroke
				(width 0.1)
				(type default)
			)
			(layer "F.Fab")
		)
		(fp_line
			(start 0.32512 0.175006)
			(end -0.32512 0.175006)
			(stroke
				(width 0.1)
				(type default)
			)
			(layer "F.Fab")
		)
		(pad "1" smd rect
			(at -0.2667 0)
			(size 0.3048 0.381)
			(layers "F.Cu" "F.Mask" "F.Paste")
			(net "SMB_RT_CPU0_P1_ROM_MUX_1D_SCL")
		)
		(pad "2" smd rect
			(at 0.2667 0 180)
			(size 0.3048 0.381)
			(layers "F.Cu" "F.Mask" "F.Paste")
			(net "SMB_RT_CPU0_P1_ROM_MUX_1D_R_SCL")
		)
	)
	(footprint ""
		(layer "F.Cu")
		(at 367.004092 -381.41783 -90)
		(property "Reference" "C896"
			(at 0 0 270)
			(layer "F.SilkS")
			(hide yes)
			(effects
				(font
					(size 1.27 1.27)
				)
			)
		)
		(property "Value" ""
			(at 0 0 270)
			(layer "F.Fab")
			(effects
				(font
					(size 1.27 1.27)
				)
			)
		)
		(duplicate_pad_numbers_are_jumpers no)
		(fp_line
			(start -0.299974 0.150114)
			(end -0.299974 -0.150114)
			(stroke
				(width 0.1)
				(type default)
			)
			(layer "F.Fab")
		)
		(fp_line
			(start 0.299974 0.150114)
			(end -0.299974 0.150114)
			(stroke
				(width 0.1)
				(type default)
			)
			(layer "F.Fab")
		)
		(fp_line
			(start -0.299974 -0.150114)
			(end 0.299974 -0.150114)
			(stroke
				(width 0.1)
				(type default)
			)
			(layer "F.Fab")
		)
		(fp_line
			(start 0.299974 -0.150114)
			(end 0.299974 0.150114)
			(stroke
				(width 0.1)
				(type default)
			)
			(layer "F.Fab")
		)
		(pad "1" smd rect
			(at -0.2667 0 270)
			(size 0.3048 0.381)
			(layers "F.Cu" "F.Mask" "F.Paste")
			(net "P5E_CPU0_P3_TX_C_DN<2>")
		)
		(pad "2" smd rect
			(at 0.2667 0 270)
			(size 0.3048 0.381)
			(layers "F.Cu" "F.Mask" "F.Paste")
			(net "P5E_CPU0_P3_TX_DN<2>")
		)
	)
)
